FILE_TYPE = MACRO_DRAWING;
SET COLOR_WIRE YELLOW;
SET COLOR_PROP MONO;
SET COLOR_DOT WHITE;
SET COLOR_ARC YELLOW;
SET COLOR_BODY GREEN;
SET COLOR_NOTE MONO;
SET PROP_DISPLAY VALUE;
SET PAGE_NUMBER P148;
FORCEADD W_VCC_CIRCLE..1
(-5875 3650);
FORCEPROP 3 LASTPIN (-5875 3650) SIG_NAME VCC_D_3V3\g
J 0
(-5865 3660);
DISPLAY 0.659574 (-5865 3660);
PAINT MONO (-5865 3660);
DISPLAY INVISIBLE (-5865 3660);
FORCEPROP 1 LAST HDL_POWER VCC_D_3V3
J 1
(-5854 3725);
DISPLAY 0.680851 (-5854 3725);
PAINT ORANGE (-5854 3725);
FORCEPROP 1 LAST PATH I10
J 0
(-5875 3650);
DISPLAY 0.617021 (-5875 3650);
PAINT GREEN (-5875 3650);
DISPLAY INVISIBLE (-5875 3650);
FORCEPROP 2 LAST CDS_LIB w_power
J 0
(-5875 3650);
PAINT MONO (-5875 3650);
DISPLAY INVISIBLE (-5875 3650);
FORCEPROP 1 LAST CDS_LMAN_SYM_OUTLINE -100,100,100,-100
J 0
(-5875 3650);
DISPLAY 0.468085 (-5875 3650);
PAINT GREEN (-5875 3650);
DISPLAY INVISIBLE (-5875 3650);
FORCEPROP 1 LAST BODY_TYPE PLUMBING
J 0
(-5863 3644);
DISPLAY 0.340426 (-5863 3644);
PAINT GREEN (-5863 3644);
DISPLAY INVISIBLE (-5863 3644);
FORCEADD OFFPAGE..1
(-5300 2450);
FORCEPROP 2 LAST $XR1 191 
J 0
(-5672 2450);
DISPLAY 0.638298 (-5672 2450);
PAINT MONO (-5672 2450);
FORCEPROP 2 LAST $XR0 118 
J 0
(-5552 2450);
DISPLAY 0.638298 (-5552 2450);
PAINT MONO (-5552 2450);
FORCEPROP 2 LAST CDS_LIB mstr_standard
J 0
(-5300 2450);
PAINT MONO (-5300 2450);
DISPLAY INVISIBLE (-5300 2450);
FORCEPROP 2 LAST BOM_COST SM_CONTROLLER
J 0
(-4850 2500);
PAINT MONO (-4850 2500);
DISPLAY INVISIBLE (-4850 2500);
FORCEPROP 2 LAST ROOM BMC
J 0
(-5550 2525);
DISPLAY 1.361702 (-5550 2525);
PAINT ORANGE (-5550 2525);
DISPLAY INVISIBLE (-5550 2525);
FORCEPROP 2 LAST PATH I12
J 0
(-5250 2525);
DISPLAY 1.021277 (-5250 2525);
PAINT ORANGE (-5250 2525);
DISPLAY INVISIBLE (-5250 2525);
FORCEPROP 1 LAST OFFPAGE TRUE
J 0
(-4975 2325);
DISPLAY 0.872340 (-4975 2325);
PAINT GREEN (-4975 2325);
DISPLAY INVISIBLE (-4975 2325);
FORCEPROP 1 LAST COMMENT_BODY TRUE
J 0
(-5175 2350);
DISPLAY 0.872340 (-5175 2350);
PAINT GREEN (-5175 2350);
DISPLAY INVISIBLE (-5175 2350);
FORCEADD OFFPAGE..1
(-5300 2400);
FORCEPROP 2 LAST $XR2 247 
J 0
(-5792 2400);
DISPLAY 0.638298 (-5792 2400);
PAINT MONO (-5792 2400);
FORCEPROP 2 LAST $XR1 190 
J 0
(-5672 2400);
DISPLAY 0.638298 (-5672 2400);
PAINT MONO (-5672 2400);
FORCEPROP 2 LAST $XR0 118 
J 0
(-5552 2400);
DISPLAY 0.638298 (-5552 2400);
PAINT MONO (-5552 2400);
FORCEPROP 2 LAST ROOM BMC
J 0
(-5550 2475);
DISPLAY 1.361702 (-5550 2475);
PAINT ORANGE (-5550 2475);
DISPLAY INVISIBLE (-5550 2475);
FORCEPROP 2 LAST BOM_COST SM_CONTROLLER
J 0
(-4850 2450);
PAINT MONO (-4850 2450);
DISPLAY INVISIBLE (-4850 2450);
FORCEPROP 2 LAST CDS_LIB mstr_standard
J 0
(-5300 2400);
PAINT MONO (-5300 2400);
DISPLAY INVISIBLE (-5300 2400);
FORCEPROP 2 LAST PATH I13
J 0
(-5250 2475);
DISPLAY 1.021277 (-5250 2475);
PAINT ORANGE (-5250 2475);
DISPLAY INVISIBLE (-5250 2475);
FORCEPROP 1 LAST OFFPAGE TRUE
J 0
(-4975 2275);
DISPLAY 0.872340 (-4975 2275);
PAINT GREEN (-4975 2275);
DISPLAY INVISIBLE (-4975 2275);
FORCEPROP 1 LAST COMMENT_BODY TRUE
J 0
(-5175 2300);
DISPLAY 0.872340 (-5175 2300);
PAINT GREEN (-5175 2300);
DISPLAY INVISIBLE (-5175 2300);
FORCEADD W_VCC_CIRCLE..1
(-5675 2900);
FORCEPROP 3 LASTPIN (-5675 2900) SIG_NAME P1V2_AUX_BMC\g
J 0
(-5665 2910);
DISPLAY 0.659574 (-5665 2910);
PAINT MONO (-5665 2910);
DISPLAY INVISIBLE (-5665 2910);
FORCEPROP 1 LAST HDL_POWER P1V2_AUX_BMC
J 1
(-5654 2975);
DISPLAY 0.680851 (-5654 2975);
PAINT ORANGE (-5654 2975);
FORCEPROP 1 LAST PATH I14
J 0
(-5675 2900);
DISPLAY 0.617021 (-5675 2900);
PAINT GREEN (-5675 2900);
DISPLAY INVISIBLE (-5675 2900);
FORCEPROP 1 LAST CDS_LMAN_SYM_OUTLINE -100,100,100,-100
J 0
(-5675 2900);
DISPLAY 0.468085 (-5675 2900);
PAINT GREEN (-5675 2900);
DISPLAY INVISIBLE (-5675 2900);
FORCEPROP 2 LAST CDS_LIB w_power
J 0
(-5675 2900);
PAINT MONO (-5675 2900);
DISPLAY INVISIBLE (-5675 2900);
FORCEPROP 1 LAST BODY_TYPE PLUMBING
J 0
(-5663 2894);
DISPLAY 0.340426 (-5663 2894);
PAINT GREEN (-5663 2894);
DISPLAY INVISIBLE (-5663 2894);
FORCEADD W_VCC_CIRCLE..1
(-6300 3950);
FORCEPROP 3 LASTPIN (-6300 3950) SIG_NAME VCC_VA_3V3\g
J 0
(-6290 3960);
DISPLAY 0.659574 (-6290 3960);
PAINT MONO (-6290 3960);
DISPLAY INVISIBLE (-6290 3960);
FORCEPROP 1 LAST HDL_POWER VCC_VA_3V3
J 1
(-6279 4025);
DISPLAY 0.680851 (-6279 4025);
PAINT ORANGE (-6279 4025);
FORCEPROP 1 LAST PATH I15
J 0
(-6300 3950);
DISPLAY 0.617021 (-6300 3950);
PAINT GREEN (-6300 3950);
DISPLAY INVISIBLE (-6300 3950);
FORCEPROP 1 LAST CDS_LMAN_SYM_OUTLINE -100,100,100,-100
J 0
(-6300 3950);
DISPLAY 0.468085 (-6300 3950);
PAINT GREEN (-6300 3950);
DISPLAY INVISIBLE (-6300 3950);
FORCEPROP 2 LAST CDS_LIB w_power
J 0
(-6300 3950);
PAINT MONO (-6300 3950);
DISPLAY INVISIBLE (-6300 3950);
FORCEPROP 1 LAST BODY_TYPE PLUMBING
J 0
(-6288 3944);
DISPLAY 0.340426 (-6288 3944);
PAINT GREEN (-6288 3944);
DISPLAY INVISIBLE (-6288 3944);
FORCEADD RES..1
(-6550 3850);
FORCEPROP 1 LAST PACK_TYPE 0402
J 0
(-6050 3850);
DISPLAY 0.617021 (-6050 3850);
PAINT SKYBLUE (-6050 3850);
FORCEPROP 1 LASTPIN (-6650 3850) $PN 1
J 0
(-6638 3862);
DISPLAY 0.787234 (-6638 3862);
PAINT ORANGE (-6638 3862);
FORCEPROP 1 LAST TOLERANCE 5%
J 0
(-6300 3850);
DISPLAY 0.617021 (-6300 3850);
PAINT SKYBLUE (-6300 3850);
FORCEPROP 1 LAST VALUE 0.0
J 2
(-6350 3850);
DISPLAY 0.617021 (-6350 3850);
PAINT SKYBLUE (-6350 3850);
FORCEPROP 1 LAST LOCATION R25W59
J 0
(-6800 3850);
DISPLAY 0.617021 (-6800 3850);
PAINT AQUA (-6800 3850);
FORCEPROP 1 LASTPIN (-6450 3850) $PN 2
J 0
(-6488 3862);
DISPLAY 0.787234 (-6488 3862);
PAINT ORANGE (-6488 3862);
FORCEPROP 1 LAST MATERIAL CHIP
J 0
(-6200 3850);
DISPLAY 0.617021 (-6200 3850);
PAINT SKYBLUE (-6200 3850);
FORCEPROP 1 LAST PART_NUMBER G21497-005
J 0
(-6825 3800);
DISPLAY 0.638298 (-6825 3800);
PAINT BLUE (-6825 3800);
FORCEPROP 1 LAST WATTAGE 1/16W
J 0
(-6550 3800);
DISPLAY 0.638298 (-6550 3800);
PAINT SKYBLUE (-6550 3800);
FORCEPROP 0 LAST ROOM USB
J 0
(-6375 3950);
DISPLAY 1.021277 (-6375 3950);
PAINT ORANGE (-6375 3950);
DISPLAY INVISIBLE (-6375 3950);
FORCEPROP 0 LAST BOM_COST MIO_USB
J 0
(-6375 4000);
DISPLAY 1.021277 (-6375 4000);
PAINT ORANGE (-6375 4000);
DISPLAY INVISIBLE (-6375 4000);
FORCEPROP 2 LAST CDS_LIB mstr_discrete
J 0
(-6550 3850);
PAINT MONO (-6550 3850);
DISPLAY INVISIBLE (-6550 3850);
FORCEPROP 0 LAST SEC 1
J 0
(-6375 3950);
DISPLAY 0.680851 (-6375 3950);
PAINT MONO (-6375 3950);
DISPLAY INVISIBLE (-6375 3950);
FORCEPROP 2 LAST SEC_TYPE 0402
J 0
(-6600 4050);
DISPLAY 1.021277 (-6600 4050);
PAINT ORANGE (-6600 4050);
DISPLAY INVISIBLE (-6600 4050);
FORCEPROP 1 LAST PATH I16
J 0
(-6600 4000);
DISPLAY 0.978723 (-6600 4000);
PAINT WHITE (-6600 4000);
DISPLAY INVISIBLE (-6600 4000);
FORCEADD P3V3_STBY..1
(-6900 4075);
FORCEPROP 3 LASTPIN (-6900 4025) SIG_NAME P3V3_STBY\g
J 0
(-6890 4035);
DISPLAY 0.659574 (-6890 4035);
PAINT MONO (-6890 4035);
DISPLAY INVISIBLE (-6890 4035);
FORCEPROP 1 LAST PATH I18
J 0
(-6855 4077);
DISPLAY 0.340426 (-6855 4077);
PAINT GREEN (-6855 4077);
DISPLAY INVISIBLE (-6855 4077);
FORCEPROP 1 LAST VOLTAGE 3.3V
J 0
(-6945 4032);
DISPLAY 0.340426 (-6945 4032);
PAINT GREEN (-6945 4032);
DISPLAY INVISIBLE (-6945 4032);
FORCEPROP 2 LAST CDS_LIB mstr_symbols
J 0
(-6900 4075);
PAINT MONO (-6900 4075);
DISPLAY INVISIBLE (-6900 4075);
FORCEPROP 1 LAST SIZE 1B
J 0
(-6855 4097);
DISPLAY 0.340426 (-6855 4097);
PAINT GREEN (-6855 4097);
DISPLAY INVISIBLE (-6855 4097);
FORCEPROP 1 LAST BODY_TYPE PLUMBING
J 0
(-6945 4032);
DISPLAY 0.340426 (-6945 4032);
PAINT GREEN (-6945 4032);
DISPLAY INVISIBLE (-6945 4032);
FORCEPROP 1 LAST HDL_POWER P3V3_STBY
J 0
(-7200 3950);
DISPLAY 0.872340 (-7200 3950);
PAINT ORANGE (-7200 3950);
DISPLAY INVISIBLE (-7200 3950);
FORCEADD W_VCC_CIRCLE..1
(-6225 2175);
FORCEPROP 3 LASTPIN (-6225 2175) SIG_NAME P1V15_AUX_BMC\g
J 0
(-6215 2185);
DISPLAY 0.659574 (-6215 2185);
PAINT MONO (-6215 2185);
DISPLAY INVISIBLE (-6215 2185);
FORCEPROP 1 LAST HDL_POWER P1V15_AUX_BMC
J 1
(-6204 2250);
DISPLAY 0.680851 (-6204 2250);
PAINT ORANGE (-6204 2250);
FORCEPROP 1 LAST PATH I19
J 0
(-6225 2175);
DISPLAY 0.617021 (-6225 2175);
PAINT GREEN (-6225 2175);
DISPLAY INVISIBLE (-6225 2175);
FORCEPROP 2 LAST CDS_LIB w_power
J 0
(-6225 2175);
PAINT MONO (-6225 2175);
DISPLAY INVISIBLE (-6225 2175);
FORCEPROP 1 LAST CDS_LMAN_SYM_OUTLINE -100,100,100,-100
J 0
(-6225 2175);
DISPLAY 0.468085 (-6225 2175);
PAINT GREEN (-6225 2175);
DISPLAY INVISIBLE (-6225 2175);
FORCEPROP 1 LAST BODY_TYPE PLUMBING
J 0
(-6213 2169);
DISPLAY 0.340426 (-6213 2169);
PAINT GREEN (-6213 2169);
DISPLAY INVISIBLE (-6213 2169);
FORCEADD P3V3_STBY..1
(-2350 4500);
FORCEPROP 3 LASTPIN (-2350 4450) SIG_NAME P3V3_STBY\g
J 0
(-2340 4460);
DISPLAY 0.659574 (-2340 4460);
PAINT MONO (-2340 4460);
DISPLAY INVISIBLE (-2340 4460);
FORCEPROP 1 LAST PATH I2
J 0
(-2305 4502);
DISPLAY 0.340426 (-2305 4502);
PAINT GREEN (-2305 4502);
DISPLAY INVISIBLE (-2305 4502);
FORCEPROP 1 LAST SIZE 1B
J 0
(-2305 4522);
DISPLAY 0.340426 (-2305 4522);
PAINT GREEN (-2305 4522);
DISPLAY INVISIBLE (-2305 4522);
FORCEPROP 1 LAST VOLTAGE 3.3V
J 0
(-2395 4457);
DISPLAY 0.340426 (-2395 4457);
PAINT GREEN (-2395 4457);
DISPLAY INVISIBLE (-2395 4457);
FORCEPROP 2 LAST CDS_LIB mstr_symbols
J 0
(-2350 4500);
PAINT MONO (-2350 4500);
DISPLAY INVISIBLE (-2350 4500);
FORCEPROP 1 LAST BODY_TYPE PLUMBING
J 0
(-2395 4457);
DISPLAY 0.340426 (-2395 4457);
PAINT GREEN (-2395 4457);
DISPLAY INVISIBLE (-2395 4457);
FORCEPROP 1 LAST HDL_POWER P3V3_STBY
J 0
(-2650 4375);
DISPLAY 0.872340 (-2650 4375);
PAINT ORANGE (-2650 4375);
DISPLAY INVISIBLE (-2650 4375);
FORCEADD CAP_A..1
(-7350 2125);
FORCEPROP 1 LAST PACK_TYPE 0402V
J 0
(-7300 1925);
DISPLAY 0.617021 (-7300 1925);
PAINT SKYBLUE (-7300 1925);
FORCEPROP 1 LAST MATERIAL X6S
J 0
(-7300 2025);
DISPLAY 0.617021 (-7300 2025);
PAINT SKYBLUE (-7300 2025);
FORCEPROP 1 LASTPIN (-7350 2225) $PN 1
J 0
(-7340 2205);
DISPLAY 0.617021 (-7340 2205);
PAINT ORANGE (-7340 2205);
FORCEPROP 1 LAST VOLTAGE 6.3V
J 0
(-7300 2125);
DISPLAY 0.617021 (-7300 2125);
PAINT SKYBLUE (-7300 2125);
FORCEPROP 1 LAST TOLERANCE 10%
J 0
(-7300 2075);
DISPLAY 0.617021 (-7300 2075);
PAINT SKYBLUE (-7300 2075);
FORCEPROP 1 LAST VALUE 1.0UF
J 0
(-7300 2175);
DISPLAY 0.617021 (-7300 2175);
PAINT SKYBLUE (-7300 2175);
FORCEPROP 1 LASTPIN (-7350 2025) $PN 2
J 0
(-7340 2005);
DISPLAY 0.617021 (-7340 2005);
PAINT ORANGE (-7340 2005);
FORCEPROP 1 LAST LOCATION C1T21
J 0
(-7300 2225);
DISPLAY 0.617021 (-7300 2225);
PAINT AQUA (-7300 2225);
FORCEPROP 1 LAST PART_NUMBER D97712-004
J 0
(-7300 1975);
DISPLAY 0.617021 (-7300 1975);
PAINT BLUE (-7300 1975);
FORCEPROP 1 LAST PATH I20
J 0
(-7300 2275);
DISPLAY 0.978723 (-7300 2275);
PAINT WHITE (-7300 2275);
DISPLAY INVISIBLE (-7300 2275);
FORCEPROP 2 LAST CDS_LOCATION C1T21
J 0
(-7300 2225);
DISPLAY 0.617021 (-7300 2225);
PAINT AQUA (-7300 2225);
DISPLAY INVISIBLE (-7300 2225);
FORCEPROP 0 LAST BOM_COST SM_CONTROLLER
J 0
(-7300 2325);
DISPLAY 1.021277 (-7300 2325);
PAINT ORANGE (-7300 2325);
DISPLAY INVISIBLE (-7300 2325);
FORCEPROP 2 LAST CDS_LIB dev_discrete
J 0
(-7350 2125);
PAINT ORANGE (-7350 2125);
DISPLAY INVISIBLE (-7350 2125);
FORCEPROP 2 LAST CDS_SEC 1
J 0
(-7300 2275);
PAINT ORANGE (-7300 2275);
DISPLAY INVISIBLE (-7300 2275);
FORCEPROP 2 LAST SEC_TYPE 0402V
J 0
(-7300 2325);
DISPLAY 1.021277 (-7300 2325);
PAINT ORANGE (-7300 2325);
DISPLAY INVISIBLE (-7300 2325);
FORCEPROP 2 LAST SEC 1
J 0
(-7300 2325);
DISPLAY 0.680851 (-7300 2325);
PAINT MONO (-7300 2325);
DISPLAY INVISIBLE (-7300 2325);
FORCEPROP 0 LAST ROOM BMC
J 0
(-7300 2275);
DISPLAY 1.021277 (-7300 2275);
PAINT ORANGE (-7300 2275);
DISPLAY INVISIBLE (-7300 2275);
FORCEADD PVCCIO_CPU0..1
(-7350 2400);
FORCEPROP 3 LASTPIN (-7350 2350) SIG_NAME PVCCIO_CPU0\g
J 0
(-7340 2360);
DISPLAY 0.659574 (-7340 2360);
PAINT MONO (-7340 2360);
DISPLAY INVISIBLE (-7340 2360);
FORCEPROP 2 LAST CDS_LIB mstr_symbols
J 0
(-7350 2400);
PAINT ORANGE (-7350 2400);
DISPLAY INVISIBLE (-7350 2400);
FORCEPROP 1 LAST VOLTAGE 1.1V
J 0
(-7395 2357);
DISPLAY 0.340426 (-7395 2357);
PAINT SKYBLUE (-7395 2357);
DISPLAY INVISIBLE (-7395 2357);
FORCEPROP 1 LAST PATH I21
J 0
(-7300 2425);
DISPLAY 0.872340 (-7300 2425);
PAINT AQUA (-7300 2425);
DISPLAY INVISIBLE (-7300 2425);
FORCEPROP 1 LAST BODY_TYPE PLUMBING
J 0
(-7395 2357);
DISPLAY 0.340426 (-7395 2357);
PAINT GREEN (-7395 2357);
DISPLAY INVISIBLE (-7395 2357);
FORCEPROP 1 LAST HDL_POWER PVCCIO_CPU0
J 1
(-7350 2450);
DISPLAY 0.872340 (-7350 2450);
PAINT GREEN (-7350 2450);
DISPLAY INVISIBLE (-7350 2450);
FORCEADD GND..1
(-7350 1875);
FORCEPROP 3 LASTPIN (-7350 1925) SIG_NAME GND\g
J 0
(-7340 1935);
DISPLAY 0.659574 (-7340 1935);
PAINT MONO (-7340 1935);
DISPLAY INVISIBLE (-7340 1935);
FORCEPROP 1 LAST PATH I22
J 0
(-7275 1875);
DISPLAY 0.872340 (-7275 1875);
PAINT AQUA (-7275 1875);
DISPLAY INVISIBLE (-7275 1875);
FORCEPROP 1 LAST VOLTAGE 0.0V
J 0
(-7395 1832);
DISPLAY 0.340426 (-7395 1832);
PAINT SKYBLUE (-7395 1832);
DISPLAY INVISIBLE (-7395 1832);
FORCEPROP 1 LAST SIZE 1B
J 0
(-7275 1825);
DISPLAY 0.872340 (-7275 1825);
PAINT AQUA (-7275 1825);
DISPLAY INVISIBLE (-7275 1825);
FORCEPROP 2 LAST CDS_LIB mstr_symbols
J 0
(-7350 1875);
PAINT ORANGE (-7350 1875);
DISPLAY INVISIBLE (-7350 1875);
FORCEPROP 1 LAST BODY_TYPE PLUMBING
J 0
(-7395 1832);
DISPLAY 0.340426 (-7395 1832);
PAINT GREEN (-7395 1832);
DISPLAY INVISIBLE (-7395 1832);
FORCEPROP 1 LAST HDL_POWER GND
J 0
(-7350 2025);
DISPLAY 0.872340 (-7350 2025);
PAINT GREEN (-7350 2025);
DISPLAY INVISIBLE (-7350 2025);
FORCEADD W_VCC_CIRCLE..1
(-5350 4400);
FORCEPROP 3 LASTPIN (-5350 4400) SIG_NAME VCC_ADCAV3V3\g
J 0
(-5340 4410);
DISPLAY 0.659574 (-5340 4410);
PAINT MONO (-5340 4410);
DISPLAY INVISIBLE (-5340 4410);
FORCEPROP 1 LAST HDL_POWER VCC_ADCAV3V3
J 1
(-5329 4475);
DISPLAY 0.680851 (-5329 4475);
PAINT ORANGE (-5329 4475);
FORCEPROP 2 LAST CDS_LIB w_power
J 0
(-5350 4400);
PAINT MONO (-5350 4400);
DISPLAY INVISIBLE (-5350 4400);
FORCEPROP 1 LAST PATH I26
J 0
(-5350 4400);
DISPLAY 0.617021 (-5350 4400);
PAINT GREEN (-5350 4400);
DISPLAY INVISIBLE (-5350 4400);
FORCEPROP 1 LAST CDS_LMAN_SYM_OUTLINE -100,100,100,-100
J 0
(-5350 4400);
DISPLAY 0.468085 (-5350 4400);
PAINT GREEN (-5350 4400);
DISPLAY INVISIBLE (-5350 4400);
FORCEPROP 1 LAST BODY_TYPE PLUMBING
J 0
(-5338 4394);
DISPLAY 0.340426 (-5338 4394);
PAINT GREEN (-5338 4394);
DISPLAY INVISIBLE (-5338 4394);
FORCEADD W_VCC_CIRCLE..1
(-5300 2050);
FORCEPROP 3 LASTPIN (-5300 2050) SIG_NAME VCC_A_1V1\g
J 0
(-5290 2060);
DISPLAY 0.659574 (-5290 2060);
PAINT MONO (-5290 2060);
DISPLAY INVISIBLE (-5290 2060);
FORCEPROP 1 LAST HDL_POWER VCC_A_1V1
J 1
(-5279 2100);
DISPLAY 0.680851 (-5279 2100);
PAINT ORANGE (-5279 2100);
FORCEPROP 1 LAST PATH I27
J 0
(-5300 2050);
DISPLAY 0.617021 (-5300 2050);
PAINT GREEN (-5300 2050);
DISPLAY INVISIBLE (-5300 2050);
FORCEPROP 1 LAST CDS_LMAN_SYM_OUTLINE -100,100,100,-100
J 0
(-5300 2050);
DISPLAY 0.468085 (-5300 2050);
PAINT GREEN (-5300 2050);
DISPLAY INVISIBLE (-5300 2050);
FORCEPROP 2 LAST CDS_LIB w_power
J 0
(-5300 2050);
PAINT MONO (-5300 2050);
DISPLAY INVISIBLE (-5300 2050);
FORCEPROP 1 LAST BODY_TYPE PLUMBING
J 0
(-5288 2044);
DISPLAY 0.340426 (-5288 2044);
PAINT GREEN (-5288 2044);
DISPLAY INVISIBLE (-5288 2044);
FORCEADD AST2520A1-GP-GP..7
(-3600 2600);
FORCEPROP 1 LAST VALUE AST2520A1-GP-GP
J 0
(-4450 450);
DISPLAY 0.617021 (-4450 450);
PAINT GREEN (-4450 450);
FORCEPROP 1 LAST $LOCATION U25W4
J 0
(-4450 4725);
DISPLAY 0.617021 (-4450 4725);
PAINT GREEN (-4450 4725);
FORCEPROP 2 LAST CDS_LIB w_hdl
J 0
(-3600 2600);
PAINT MONO (-3600 2600);
DISPLAY INVISIBLE (-3600 2600);
FORCEPROP 1 LAST PART_NUMBER 071.2520A.M001
J 0
(-3600 2600);
DISPLAY 0.617021 (-3600 2600);
PAINT GREEN (-3600 2600);
DISPLAY INVISIBLE (-3600 2600);
FORCEPROP 1 LAST PATH I28
J 0
(-3600 2600);
DISPLAY 0.617021 (-3600 2600);
PAINT GREEN (-3600 2600);
DISPLAY INVISIBLE (-3600 2600);
FORCEPROP 1 LAST PACK_TYPE ASIC2-GB1
J 0
(-3600 2600);
DISPLAY 0.617021 (-3600 2600);
PAINT GREEN (-3600 2600);
DISPLAY INVISIBLE (-3600 2600);
FORCEPROP 1 LAST CDS_LMAN_SYM_OUTLINE -850,2100,850,-2100
J 0
(-3600 2600);
DISPLAY 0.468085 (-3600 2600);
PAINT GREEN (-3600 2600);
DISPLAY INVISIBLE (-3600 2600);
FORCEADD RES..1
(-6850 2300);
FORCEPROP 1 LAST TOLERANCE 5%
J 0
(-6600 2300);
DISPLAY 0.617021 (-6600 2300);
PAINT SKYBLUE (-6600 2300);
FORCEPROP 1 LAST MATERIAL CHIP
J 0
(-6500 2300);
DISPLAY 0.617021 (-6500 2300);
PAINT SKYBLUE (-6500 2300);
FORCEPROP 1 LAST PACK_TYPE 0402
J 0
(-6350 2300);
DISPLAY 0.617021 (-6350 2300);
PAINT SKYBLUE (-6350 2300);
FORCEPROP 1 LAST VALUE 0.0
J 2
(-6650 2300);
DISPLAY 0.617021 (-6650 2300);
PAINT SKYBLUE (-6650 2300);
FORCEPROP 1 LAST WATTAGE 1/16W
J 0
(-6850 2250);
DISPLAY 0.638298 (-6850 2250);
PAINT SKYBLUE (-6850 2250);
FORCEPROP 1 LASTPIN (-6950 2300) $PN 1
J 0
(-6938 2312);
DISPLAY 0.787234 (-6938 2312);
PAINT ORANGE (-6938 2312);
FORCEPROP 1 LASTPIN (-6750 2300) $PN 2
J 0
(-6788 2312);
DISPLAY 0.787234 (-6788 2312);
PAINT ORANGE (-6788 2312);
FORCEPROP 1 LAST PART_NUMBER G21497-005
J 0
(-7000 2375);
DISPLAY 0.638298 (-7000 2375);
PAINT BLUE (-7000 2375);
FORCEPROP 1 LAST LOCATION R25W155
J 0
(-6975 2425);
DISPLAY 0.617021 (-6975 2425);
PAINT AQUA (-6975 2425);
FORCEPROP 1 LAST PATH I29
J 0
(-6900 2450);
DISPLAY 0.978723 (-6900 2450);
PAINT WHITE (-6900 2450);
DISPLAY INVISIBLE (-6900 2450);
FORCEPROP 0 LAST ROOM USB
J 0
(-6675 2400);
DISPLAY 1.021277 (-6675 2400);
PAINT ORANGE (-6675 2400);
DISPLAY INVISIBLE (-6675 2400);
FORCEPROP 0 LAST BOM_COST MIO_USB
J 0
(-6675 2450);
DISPLAY 1.021277 (-6675 2450);
PAINT ORANGE (-6675 2450);
DISPLAY INVISIBLE (-6675 2450);
FORCEPROP 2 LAST CDS_LIB mstr_discrete
J 0
(-6850 2300);
PAINT MONO (-6850 2300);
DISPLAY INVISIBLE (-6850 2300);
FORCEPROP 0 LAST SEC 1
J 0
(-6675 2400);
DISPLAY 0.680851 (-6675 2400);
PAINT MONO (-6675 2400);
DISPLAY INVISIBLE (-6675 2400);
FORCEPROP 2 LAST SEC_TYPE 0402
J 0
(-6900 2500);
DISPLAY 1.021277 (-6900 2500);
PAINT ORANGE (-6900 2500);
DISPLAY INVISIBLE (-6900 2500);
FORCEADD GND..1
(-2350 500);
FORCEPROP 3 LASTPIN (-2350 550) SIG_NAME GND\g
J 0
(-2340 560);
DISPLAY 0.659574 (-2340 560);
PAINT MONO (-2340 560);
DISPLAY INVISIBLE (-2340 560);
FORCEPROP 1 LAST PATH I3
J 0
(-2275 500);
DISPLAY 0.872340 (-2275 500);
PAINT AQUA (-2275 500);
DISPLAY INVISIBLE (-2275 500);
FORCEPROP 2 LAST CDS_LIB mstr_symbols
J 0
(-2350 500);
PAINT MONO (-2350 500);
DISPLAY INVISIBLE (-2350 500);
FORCEPROP 1 LAST SIZE 1B
J 0
(-2275 450);
DISPLAY 0.872340 (-2275 450);
PAINT AQUA (-2275 450);
DISPLAY INVISIBLE (-2275 450);
FORCEPROP 1 LAST VOLTAGE 0.0V
J 0
(-2395 457);
DISPLAY 0.340426 (-2395 457);
PAINT GREEN (-2395 457);
DISPLAY INVISIBLE (-2395 457);
FORCEPROP 1 LAST BODY_TYPE PLUMBING
J 0
(-2395 457);
DISPLAY 0.340426 (-2395 457);
PAINT GREEN (-2395 457);
DISPLAY INVISIBLE (-2395 457);
FORCEPROP 1 LAST HDL_POWER GND
J 0
(-2350 650);
DISPLAY 0.872340 (-2350 650);
PAINT GREEN (-2350 650);
DISPLAY INVISIBLE (-2350 650);
FORCEADD OFFPAGE..5
(-5300 2500);
FORCEPROP 2 LAST $XR2 255 
J 0
(-5795 2500);
DISPLAY 0.638298 (-5795 2500);
PAINT MONO (-5795 2500);
FORCEPROP 2 LAST $XR1 254 
J 0
(-5675 2500);
DISPLAY 0.638298 (-5675 2500);
PAINT MONO (-5675 2500);
FORCEPROP 2 LAST $XR0 189 
J 0
(-5555 2500);
DISPLAY 0.638298 (-5555 2500);
PAINT MONO (-5555 2500);
FORCEPROP 2 LAST CDS_LIB mstr_standard
J 0
(-5300 2500);
PAINT ORANGE (-5300 2500);
DISPLAY INVISIBLE (-5300 2500);
FORCEPROP 2 LAST PATH I30
J 0
(-5575 2550);
DISPLAY 1.021277 (-5575 2550);
PAINT ORANGE (-5575 2550);
DISPLAY INVISIBLE (-5575 2550);
FORCEPROP 1 LAST OFFPAGE TRUE
J 0
(-4975 2375);
DISPLAY 0.872340 (-4975 2375);
PAINT GREEN (-4975 2375);
DISPLAY INVISIBLE (-4975 2375);
FORCEPROP 1 LAST COMMENT_BODY TRUE
J 0
(-5200 2425);
DISPLAY 0.872340 (-5200 2425);
PAINT GREEN (-5200 2425);
DISPLAY INVISIBLE (-5200 2425);
FORCEADD P3V3_STBY..1
(-4950 4650);
FORCEPROP 3 LASTPIN (-4950 4600) SIG_NAME P3V3_STBY\g
J 0
(-4940 4610);
DISPLAY 0.659574 (-4940 4610);
PAINT MONO (-4940 4610);
DISPLAY INVISIBLE (-4940 4610);
FORCEPROP 1 LAST VOLTAGE 3.3V
J 0
(-4995 4607);
DISPLAY 0.340426 (-4995 4607);
PAINT GREEN (-4995 4607);
DISPLAY INVISIBLE (-4995 4607);
FORCEPROP 1 LAST SIZE 1B
J 0
(-4905 4672);
DISPLAY 0.340426 (-4905 4672);
PAINT GREEN (-4905 4672);
DISPLAY INVISIBLE (-4905 4672);
FORCEPROP 2 LAST CDS_LIB mstr_symbols
J 0
(-4950 4650);
PAINT MONO (-4950 4650);
DISPLAY INVISIBLE (-4950 4650);
FORCEPROP 1 LAST PATH I4
J 0
(-4905 4652);
DISPLAY 0.340426 (-4905 4652);
PAINT GREEN (-4905 4652);
DISPLAY INVISIBLE (-4905 4652);
FORCEPROP 1 LAST BODY_TYPE PLUMBING
J 0
(-4995 4607);
DISPLAY 0.340426 (-4995 4607);
PAINT GREEN (-4995 4607);
DISPLAY INVISIBLE (-4995 4607);
FORCEPROP 1 LAST HDL_POWER P3V3_STBY
J 0
(-5250 4525);
DISPLAY 0.872340 (-5250 4525);
PAINT ORANGE (-5250 4525);
DISPLAY INVISIBLE (-5250 4525);
FORCEADD W_VCC_CIRCLE..1
(-6000 4300);
FORCEPROP 3 LASTPIN (-6000 4300) SIG_NAME VCC_DACAV3V3\g
J 0
(-5990 4310);
DISPLAY 0.659574 (-5990 4310);
PAINT MONO (-5990 4310);
DISPLAY INVISIBLE (-5990 4310);
FORCEPROP 1 LAST HDL_POWER VCC_DACAV3V3
J 1
(-5979 4375);
DISPLAY 0.680851 (-5979 4375);
PAINT ORANGE (-5979 4375);
FORCEPROP 2 LAST CDS_LIB w_power
J 0
(-6000 4300);
PAINT MONO (-6000 4300);
DISPLAY INVISIBLE (-6000 4300);
FORCEPROP 1 LAST CDS_LMAN_SYM_OUTLINE -100,100,100,-100
J 0
(-6000 4300);
DISPLAY 0.468085 (-6000 4300);
PAINT GREEN (-6000 4300);
DISPLAY INVISIBLE (-6000 4300);
FORCEPROP 1 LAST PATH I6
J 0
(-6000 4300);
DISPLAY 0.617021 (-6000 4300);
PAINT GREEN (-6000 4300);
DISPLAY INVISIBLE (-6000 4300);
FORCEPROP 1 LAST BODY_TYPE PLUMBING
J 0
(-5988 4294);
DISPLAY 0.340426 (-5988 4294);
PAINT GREEN (-5988 4294);
DISPLAY INVISIBLE (-5988 4294);
FORCEADD W_VCC_CIRCLE..1
(-6400 4200);
FORCEPROP 3 LASTPIN (-6400 4200) SIG_NAME P3V3_USB2A_ALG\g
J 0
(-6390 4210);
DISPLAY 0.659574 (-6390 4210);
PAINT MONO (-6390 4210);
DISPLAY INVISIBLE (-6390 4210);
FORCEPROP 1 LAST HDL_POWER P3V3_USB2A_ALG
J 1
(-6379 4275);
DISPLAY 0.680851 (-6379 4275);
PAINT ORANGE (-6379 4275);
FORCEPROP 1 LAST PATH I7
J 0
(-6400 4200);
DISPLAY 0.617021 (-6400 4200);
PAINT GREEN (-6400 4200);
DISPLAY INVISIBLE (-6400 4200);
FORCEPROP 1 LAST CDS_LMAN_SYM_OUTLINE -100,100,100,-100
J 0
(-6400 4200);
DISPLAY 0.468085 (-6400 4200);
PAINT GREEN (-6400 4200);
DISPLAY INVISIBLE (-6400 4200);
FORCEPROP 2 LAST CDS_LIB w_power
J 0
(-6400 4200);
PAINT MONO (-6400 4200);
DISPLAY INVISIBLE (-6400 4200);
FORCEPROP 1 LAST BODY_TYPE PLUMBING
J 0
(-6388 4194);
DISPLAY 0.340426 (-6388 4194);
PAINT GREEN (-6388 4194);
DISPLAY INVISIBLE (-6388 4194);
FORCEADD W_VCC_CIRCLE..1
(-5025 3725);
FORCEPROP 3 LASTPIN (-5025 3725) SIG_NAME VCC_PA_3V3\g
J 0
(-5015 3735);
DISPLAY 0.659574 (-5015 3735);
PAINT MONO (-5015 3735);
DISPLAY INVISIBLE (-5015 3735);
FORCEPROP 1 LAST HDL_POWER VCC_PA_3V3
J 1
(-5029 3800);
DISPLAY 0.680851 (-5029 3800);
PAINT ORANGE (-5029 3800);
FORCEPROP 1 LAST PATH I8
J 0
(-5025 3725);
DISPLAY 0.617021 (-5025 3725);
PAINT GREEN (-5025 3725);
DISPLAY INVISIBLE (-5025 3725);
FORCEPROP 1 LAST CDS_LMAN_SYM_OUTLINE -100,100,100,-100
J 0
(-5025 3725);
DISPLAY 0.468085 (-5025 3725);
PAINT GREEN (-5025 3725);
DISPLAY INVISIBLE (-5025 3725);
FORCEPROP 2 LAST CDS_LIB w_power
J 0
(-5025 3725);
PAINT MONO (-5025 3725);
DISPLAY INVISIBLE (-5025 3725);
FORCEPROP 1 LAST BODY_TYPE PLUMBING
J 0
(-5013 3719);
DISPLAY 0.340426 (-5013 3719);
PAINT GREEN (-5013 3719);
DISPLAY INVISIBLE (-5013 3719);
FORCEADD W_VCC_CIRCLE..1
(-5350 4000);
FORCEPROP 3 LASTPIN (-5350 4000) SIG_NAME VCC_D_3V3\g
J 0
(-5340 4010);
DISPLAY 0.659574 (-5340 4010);
PAINT MONO (-5340 4010);
DISPLAY INVISIBLE (-5340 4010);
FORCEPROP 1 LAST HDL_POWER VCC_D_3V3
J 1
(-5529 4025);
DISPLAY 0.680851 (-5529 4025);
PAINT ORANGE (-5529 4025);
FORCEPROP 1 LAST PATH I9
J 0
(-5350 4000);
DISPLAY 0.617021 (-5350 4000);
PAINT GREEN (-5350 4000);
DISPLAY INVISIBLE (-5350 4000);
FORCEPROP 2 LAST CDS_LIB w_power
J 0
(-5350 4000);
PAINT MONO (-5350 4000);
DISPLAY INVISIBLE (-5350 4000);
FORCEPROP 1 LAST CDS_LMAN_SYM_OUTLINE -100,100,100,-100
J 0
(-5350 4000);
DISPLAY 0.468085 (-5350 4000);
PAINT GREEN (-5350 4000);
DISPLAY INVISIBLE (-5350 4000);
FORCEPROP 1 LAST BODY_TYPE PLUMBING
J 0
(-5338 3994);
DISPLAY 0.340426 (-5338 3994);
PAINT GREEN (-5338 3994);
DISPLAY INVISIBLE (-5338 3994);
FORCEADD INTEL_CORP_BPAGE..1
(0 0);
FORCEPROP 1 LAST CDS_CON_LAST_MODIFIED Fri Jun 16 17:48:55 2017
J 0
(-1425 325);
DISPLAY 1.361702 (-1425 325);
PAINT GREEN (-1425 325);
DISPLAY INVISIBLE (-1425 325);
FORCEPROP 1 LAST CUSTOM_TXT_CDS <CURRENT_DESIGN_SHEET> OF <TOTAL_DESIGN_SHEETS>
J 0
(-500 25);
PAINT ORANGE (-500 25);
FORCEPROP 1 LAST CUSTOM_TXT_CDS <CON_LAST_MODIFIED>
J 0
(-4000 100);
PAINT ORANGE (-4000 100);
FORCEPROP 2 LAST CUSTOM_TXT_CDS <XR_PAGE_TITLE>
J 0
(-7890 5250);
DISPLAY 0.638298 (-7890 5250);
PAINT PINK (-7890 5250);
DISPLAY INVISIBLE (-7890 5250);
FORCEPROP 1 LAST SCH_TITLE BMC (7 OF 7)
J 0
(-7950 50);
DISPLAY 1.212766 (-7950 50);
PAINT ORANGE (-7950 50);
FORCEPROP 2 LAST CDS_LIB mstr_symbols
J 0
(0 0);
DISPLAY 1.361702 (0 0);
PAINT ORANGE (0 0);
DISPLAY INVISIBLE (0 0);
FORCEPROP 2 LAST PAGE_BORDER TRUE
J 0
(-7890 5250);
DISPLAY 0.851064 (-7890 5250);
PAINT PINK (-7890 5250);
DISPLAY INVISIBLE (-7890 5250);
FORCEPROP 1 LAST COMMENT_BODY TRUE
J 0
(12 12);
DISPLAY 0.617021 (12 12);
PAINT GREEN (12 12);
DISPLAY INVISIBLE (12 12);
FORCEPROP 2 LAST CDS_XR_PAGE_TITLE CR-148 : @BASEBOARD_FAB2_LIB.BASEBOARD_FAB2(SCH_1):PAGE148
J 0
(-7890 5250);
DISPLAY 0.638298 (-7890 5250);
PAINT PINK (-7890 5250);
DISPLAY INVISIBLE (-7890 5250);
WIRE 16 -1 (-5875 3650)(-5875 3600);
WIRE 16 -1 (-4950 3600)(-5875 3600);
WIRE 16 -1 (-4950 3500)(-4950 3600);
WIRE 16 -1 (-4950 3600)(-4600 3600);
WIRE 16 -1 (-4950 3450)(-4950 3500);
WIRE 16 -1 (-4950 3500)(-4600 3500);
WIRE 16 -1 (-4950 3400)(-4950 3450);
WIRE 16 -1 (-4950 3450)(-4600 3450);
WIRE 16 -1 (-4950 3350)(-4950 3400);
WIRE 16 -1 (-4950 3400)(-4600 3400);
WIRE 16 -1 (-4950 3300)(-4950 3350);
WIRE 16 -1 (-4950 3350)(-4600 3350);
WIRE 16 -1 (-4950 3250)(-4950 3300);
WIRE 16 -1 (-4950 3300)(-4600 3300);
WIRE 16 -1 (-4950 3200)(-4950 3250);
WIRE 16 -1 (-4950 3250)(-4600 3250);
WIRE 16 -1 (-4950 3150)(-4950 3200);
WIRE 16 -1 (-4950 3200)(-4600 3200);
WIRE 16 -1 (-4950 3100)(-4950 3150);
WIRE 16 -1 (-4950 3150)(-4600 3150);
WIRE 16 -1 (-4950 3050)(-4950 3100);
WIRE 16 -1 (-4950 3100)(-4600 3100);
WIRE 16 -1 (-4950 3000)(-4950 3050);
WIRE 16 -1 (-4950 3050)(-4600 3050);
WIRE 16 -1 (-4950 2950)(-4950 3000);
WIRE 16 -1 (-4950 3000)(-4600 3000);
WIRE 16 -1 (-4950 2900)(-4950 2950);
WIRE 16 -1 (-4950 2950)(-4600 2950);
WIRE 16 -1 (-4600 2900)(-4950 2900);
WIRE 16 -1 (-5675 2900)(-5675 2800);
WIRE 16 -1 (-5675 2800)(-5675 2750);
WIRE 16 -1 (-4600 2800)(-5675 2800);
WIRE 16 -1 (-5675 2750)(-5675 2700);
WIRE 16 -1 (-4600 2750)(-5675 2750);
WIRE 16 -1 (-5675 2700)(-5675 2650);
WIRE 16 -1 (-4600 2700)(-5675 2700);
WIRE 16 -1 (-5675 2650)(-5675 2600);
WIRE 16 -1 (-4600 2650)(-5675 2650);
WIRE 16 -1 (-5675 2600)(-4600 2600);
WIRE 16 -1 (-6300 3950)(-4700 3950);
WIRE 16 -1 (-4700 3950)(-4700 3900);
WIRE 16 -1 (-4700 3950)(-4600 3950);
WIRE 16 -1 (-4700 3900)(-4600 3900);
WIRE 16 -1 (-6900 3850)(-6900 4025);
WIRE 16 -1 (-6650 3850)(-6900 3850);
WIRE 16 -1 (-6225 2100)(-6225 2175);
WIRE 16 -1 (-5700 2100)(-6225 2100);
WIRE 16 -1 (-5700 1900)(-5700 2100);
WIRE 16 -1 (-5700 2100)(-5700 2150);
WIRE 16 -1 (-5700 2250)(-5700 2150);
WIRE 16 -1 (-5700 2150)(-4600 2150);
WIRE 16 -1 (-5700 1850)(-5700 1900);
WIRE 16 -1 (-4600 1900)(-5700 1900);
WIRE 16 -1 (-5700 1850)(-5700 1800);
WIRE 16 -1 (-4600 1850)(-5700 1850);
WIRE 16 -1 (-4600 2250)(-5700 2250);
WIRE 16 -1 (-5700 1800)(-5700 1750);
WIRE 16 -1 (-4600 1800)(-5700 1800);
WIRE 16 -1 (-5700 1750)(-5700 1700);
WIRE 16 -1 (-4600 1750)(-5700 1750);
WIRE 16 -1 (-5700 1700)(-5700 1650);
WIRE 16 -1 (-4600 1700)(-5700 1700);
WIRE 16 -1 (-5700 1650)(-5700 1600);
WIRE 16 -1 (-4600 1650)(-5700 1650);
WIRE 16 -1 (-5700 1600)(-5700 1550);
WIRE 16 -1 (-4600 1600)(-5700 1600);
WIRE 16 -1 (-5700 1550)(-5700 1500);
WIRE 16 -1 (-4600 1550)(-5700 1550);
WIRE 16 -1 (-5700 1500)(-5700 1450);
WIRE 16 -1 (-4600 1500)(-5700 1500);
WIRE 16 -1 (-5700 1450)(-5700 1400);
WIRE 16 -1 (-4600 1450)(-5700 1450);
WIRE 16 -1 (-5700 1400)(-5700 1350);
WIRE 16 -1 (-4600 1400)(-5700 1400);
WIRE 16 -1 (-5700 1350)(-5700 1300);
WIRE 16 -1 (-4600 1350)(-5700 1350);
WIRE 16 -1 (-5700 1300)(-5700 1250);
WIRE 16 -1 (-4600 1300)(-5700 1300);
WIRE 16 -1 (-5700 1250)(-5700 1200);
WIRE 16 -1 (-4600 1250)(-5700 1250);
WIRE 16 -1 (-5700 1200)(-5700 1150);
WIRE 16 -1 (-4600 1200)(-5700 1200);
WIRE 16 -1 (-5700 1150)(-5700 1100);
WIRE 16 -1 (-4600 1150)(-5700 1150);
WIRE 16 -1 (-5700 1100)(-5700 1050);
WIRE 16 -1 (-4600 1100)(-5700 1100);
WIRE 16 -1 (-5700 1050)(-5700 1000);
WIRE 16 -1 (-4600 1050)(-5700 1050);
WIRE 16 -1 (-5700 1000)(-5700 950);
WIRE 16 -1 (-4600 1000)(-5700 1000);
WIRE 16 -1 (-5700 950)(-5700 900);
WIRE 16 -1 (-4600 950)(-5700 950);
WIRE 16 -1 (-5700 900)(-5700 850);
WIRE 16 -1 (-4600 900)(-5700 900);
WIRE 16 -1 (-5700 850)(-5700 800);
WIRE 16 -1 (-4600 850)(-5700 850);
WIRE 16 -1 (-5700 800)(-5700 750);
WIRE 16 -1 (-4600 800)(-5700 800);
WIRE 16 -1 (-5700 750)(-5700 700);
WIRE 16 -1 (-4600 750)(-5700 750);
WIRE 16 -1 (-4600 700)(-5700 700);
WIRE 16 -1 (-2350 4450)(-2350 4400);
WIRE 16 -1 (-2350 4400)(-2350 4350);
WIRE 16 -1 (-2350 4400)(-2600 4400);
WIRE 16 -1 (-2600 4350)(-2350 4350);
WIRE 16 -1 (-7350 2300)(-7350 2350);
WIRE 16 -1 (-7350 2225)(-7350 2300);
WIRE 16 -1 (-7350 2300)(-6950 2300);
WIRE 16 -1 (-7350 2025)(-7350 1925);
WIRE 16 -1 (-5350 4300)(-5350 4400);
WIRE 16 -1 (-5350 4300)(-4600 4300);
WIRE 16 -1 (-5300 2050)(-5300 2000);
WIRE 16 -1 (-4700 2000)(-5300 2000);
WIRE 16 -1 (-4700 2050)(-4700 2000);
WIRE 16 -1 (-4600 2000)(-4700 2000);
WIRE 16 -1 (-4700 2050)(-4600 2050);
WIRE 16 -1 (-2350 700)(-2350 550);
WIRE 16 -1 (-2350 750)(-2350 700);
WIRE 16 -1 (-2600 700)(-2350 700);
WIRE 16 -1 (-2350 800)(-2350 750);
WIRE 16 -1 (-2600 750)(-2350 750);
WIRE 16 -1 (-2350 850)(-2350 800);
WIRE 16 -1 (-2600 800)(-2350 800);
WIRE 16 -1 (-2350 900)(-2350 850);
WIRE 16 -1 (-2600 850)(-2350 850);
WIRE 16 -1 (-2350 950)(-2350 900);
WIRE 16 -1 (-2600 900)(-2350 900);
WIRE 16 -1 (-2350 1000)(-2350 950);
WIRE 16 -1 (-2600 950)(-2350 950);
WIRE 16 -1 (-2350 1050)(-2350 1000);
WIRE 16 -1 (-2600 1000)(-2350 1000);
WIRE 16 -1 (-2350 1100)(-2350 1050);
WIRE 16 -1 (-2600 1050)(-2350 1050);
WIRE 16 -1 (-2350 1150)(-2350 1100);
WIRE 16 -1 (-2600 1100)(-2350 1100);
WIRE 16 -1 (-2350 1200)(-2350 1150);
WIRE 16 -1 (-2600 1150)(-2350 1150);
WIRE 16 -1 (-2350 1250)(-2350 1200);
WIRE 16 -1 (-2600 1200)(-2350 1200);
WIRE 16 -1 (-2350 1300)(-2350 1250);
WIRE 16 -1 (-2600 1250)(-2350 1250);
WIRE 16 -1 (-2350 1350)(-2350 1300);
WIRE 16 -1 (-2600 1300)(-2350 1300);
WIRE 16 -1 (-2350 1400)(-2350 1350);
WIRE 16 -1 (-2600 1350)(-2350 1350);
WIRE 16 -1 (-2350 1450)(-2350 1400);
WIRE 16 -1 (-2600 1400)(-2350 1400);
WIRE 16 -1 (-2350 1500)(-2350 1450);
WIRE 16 -1 (-2600 1450)(-2350 1450);
WIRE 16 -1 (-2350 1550)(-2350 1500);
WIRE 16 -1 (-2600 1500)(-2350 1500);
WIRE 16 -1 (-2350 1600)(-2350 1550);
WIRE 16 -1 (-2600 1550)(-2350 1550);
WIRE 16 -1 (-2350 1650)(-2350 1600);
WIRE 16 -1 (-2600 1600)(-2350 1600);
WIRE 16 -1 (-2350 1700)(-2350 1650);
WIRE 16 -1 (-2600 1650)(-2350 1650);
WIRE 16 -1 (-2350 1750)(-2350 1700);
WIRE 16 -1 (-2600 1700)(-2350 1700);
WIRE 16 -1 (-2350 1800)(-2350 1750);
WIRE 16 -1 (-2600 1750)(-2350 1750);
WIRE 16 -1 (-2350 1850)(-2350 1800);
WIRE 16 -1 (-2600 1800)(-2350 1800);
WIRE 16 -1 (-2350 1900)(-2350 1850);
WIRE 16 -1 (-2600 1850)(-2350 1850);
WIRE 16 -1 (-2350 1950)(-2350 1900);
WIRE 16 -1 (-2600 1900)(-2350 1900);
WIRE 16 -1 (-2350 2000)(-2350 1950);
WIRE 16 -1 (-2600 1950)(-2350 1950);
WIRE 16 -1 (-2350 2050)(-2350 2000);
WIRE 16 -1 (-2600 2000)(-2350 2000);
WIRE 16 -1 (-2350 2100)(-2350 2050);
WIRE 16 -1 (-2600 2050)(-2350 2050);
WIRE 16 -1 (-2350 2150)(-2350 2100);
WIRE 16 -1 (-2600 2100)(-2350 2100);
WIRE 16 -1 (-2350 2200)(-2350 2150);
WIRE 16 -1 (-2600 2150)(-2350 2150);
WIRE 16 -1 (-2350 2250)(-2350 2200);
WIRE 16 -1 (-2600 2200)(-2350 2200);
WIRE 16 -1 (-2350 2300)(-2350 2250);
WIRE 16 -1 (-2600 2250)(-2350 2250);
WIRE 16 -1 (-2350 2350)(-2350 2300);
WIRE 16 -1 (-2600 2300)(-2350 2300);
WIRE 16 -1 (-2350 2400)(-2350 2350);
WIRE 16 -1 (-2600 2350)(-2350 2350);
WIRE 16 -1 (-2350 2450)(-2350 2400);
WIRE 16 -1 (-2600 2400)(-2350 2400);
WIRE 16 -1 (-2350 2500)(-2350 2450);
WIRE 16 -1 (-2600 2450)(-2350 2450);
WIRE 16 -1 (-2350 2550)(-2350 2500);
WIRE 16 -1 (-2600 2500)(-2350 2500);
WIRE 16 -1 (-2350 2600)(-2350 2550);
WIRE 16 -1 (-2600 2550)(-2350 2550);
WIRE 16 -1 (-2350 2650)(-2350 2600);
WIRE 16 -1 (-2600 2600)(-2350 2600);
WIRE 16 -1 (-2350 2700)(-2350 2650);
WIRE 16 -1 (-2600 2650)(-2350 2650);
WIRE 16 -1 (-2350 2750)(-2350 2700);
WIRE 16 -1 (-2600 2700)(-2350 2700);
WIRE 16 -1 (-2350 2800)(-2350 2750);
WIRE 16 -1 (-2600 2750)(-2350 2750);
WIRE 16 -1 (-2350 2850)(-2350 2800);
WIRE 16 -1 (-2600 2800)(-2350 2800);
WIRE 16 -1 (-2350 2900)(-2350 2850);
WIRE 16 -1 (-2600 2850)(-2350 2850);
WIRE 16 -1 (-2350 2950)(-2350 2900);
WIRE 16 -1 (-2600 2900)(-2350 2900);
WIRE 16 -1 (-2350 3000)(-2350 2950);
WIRE 16 -1 (-2600 2950)(-2350 2950);
WIRE 16 -1 (-2350 3050)(-2350 3000);
WIRE 16 -1 (-2600 3000)(-2350 3000);
WIRE 16 -1 (-2350 3100)(-2350 3050);
WIRE 16 -1 (-2600 3050)(-2350 3050);
WIRE 16 -1 (-2350 3150)(-2350 3100);
WIRE 16 -1 (-2600 3100)(-2350 3100);
WIRE 16 -1 (-2350 3200)(-2350 3150);
WIRE 16 -1 (-2600 3150)(-2350 3150);
WIRE 16 -1 (-2350 3250)(-2350 3200);
WIRE 16 -1 (-2600 3200)(-2350 3200);
WIRE 16 -1 (-2350 3300)(-2350 3250);
WIRE 16 -1 (-2600 3250)(-2350 3250);
WIRE 16 -1 (-2350 3350)(-2350 3300);
WIRE 16 -1 (-2600 3300)(-2350 3300);
WIRE 16 -1 (-2350 3400)(-2350 3350);
WIRE 16 -1 (-2600 3350)(-2350 3350);
WIRE 16 -1 (-2350 3450)(-2350 3400);
WIRE 16 -1 (-2600 3400)(-2350 3400);
WIRE 16 -1 (-2350 3500)(-2350 3450);
WIRE 16 -1 (-2600 3450)(-2350 3450);
WIRE 16 -1 (-2350 3550)(-2350 3500);
WIRE 16 -1 (-2600 3500)(-2350 3500);
WIRE 16 -1 (-2350 3600)(-2350 3550);
WIRE 16 -1 (-2600 3550)(-2350 3550);
WIRE 16 -1 (-2350 3650)(-2350 3600);
WIRE 16 -1 (-2600 3600)(-2350 3600);
WIRE 16 -1 (-2350 3700)(-2350 3650);
WIRE 16 -1 (-2600 3650)(-2350 3650);
WIRE 16 -1 (-2350 3750)(-2350 3700);
WIRE 16 -1 (-2600 3700)(-2350 3700);
WIRE 16 -1 (-2350 3800)(-2350 3750);
WIRE 16 -1 (-2600 3750)(-2350 3750);
WIRE 16 -1 (-2350 3850)(-2350 3800);
WIRE 16 -1 (-2600 3800)(-2350 3800);
WIRE 16 -1 (-2350 3900)(-2350 3850);
WIRE 16 -1 (-2600 3850)(-2350 3850);
WIRE 16 -1 (-2350 3950)(-2350 3900);
WIRE 16 -1 (-2600 3900)(-2350 3900);
WIRE 16 -1 (-2350 4000)(-2350 3950);
WIRE 16 -1 (-2600 3950)(-2350 3950);
WIRE 16 -1 (-2350 4050)(-2350 4000);
WIRE 16 -1 (-2600 4000)(-2350 4000);
WIRE 16 -1 (-2350 4100)(-2350 4050);
WIRE 16 -1 (-2600 4050)(-2350 4050);
WIRE 16 -1 (-2350 4100)(-2600 4100);
WIRE 16 -1 (-4950 4600)(-4950 4550);
WIRE 16 -1 (-4950 4550)(-4825 4550);
WIRE 16 -1 (-4825 4550)(-4825 4500);
WIRE 16 -1 (-4600 4550)(-4825 4550);
WIRE 16 -1 (-4825 4500)(-4825 4450);
WIRE 16 -1 (-4600 4500)(-4825 4500);
WIRE 16 -1 (-4825 4450)(-4825 4400);
WIRE 16 -1 (-4600 4450)(-4825 4450);
WIRE 16 -1 (-4600 4400)(-4825 4400);
WIRE 16 -1 (-6000 4250)(-6000 4300);
WIRE 16 -1 (-6000 4200)(-6000 4250);
WIRE 16 -1 (-6000 4250)(-4600 4250);
WIRE 16 -1 (-4600 4200)(-6000 4200);
WIRE 16 -1 (-6400 4100)(-6400 4200);
WIRE 16 -1 (-4600 4100)(-6400 4100);
WIRE 16 -1 (-5025 3700)(-5025 3725);
WIRE 16 -1 (-4750 3700)(-5025 3700);
WIRE 16 -1 (-4750 3700)(-4750 3550);
WIRE 16 -1 (-4750 3700)(-4750 3750);
WIRE 16 -1 (-4600 3700)(-4750 3700);
WIRE 16 -1 (-4750 3750)(-4600 3750);
WIRE 16 -1 (-4600 3550)(-4750 3550);
WIRE 16 -1 (-5350 4000)(-4600 4000);
WIRE 16 -1 (-6750 2300)(-4600 2300);
FORCEPROP 2 LAST SIG_NAME PVCCIO_CPU0_R
J 0
(-5960 2310);
DISPLAY 0.638298 (-5960 2310);
PAINT ORANGE (-5960 2310);
FORCEPROP 2 LASTPROP $XRERR UNIQUE?
J 0
(-6200 2310);
DISPLAY 0.638298 (-6200 2310);
PAINT MONO (-6200 2310);
DISPLAY INVISIBLE (-6200 2310);
WIRE 16 -1 (-5250 2400)(-4600 2400);
FORCEPROP 2 LAST SIG_NAME FM_SLPS3_N
J 2
(-4975 2410);
DISPLAY 0.617021 (-4975 2410);
PAINT ORANGE (-4975 2410);
WIRE 16 -1 (-5250 2450)(-4600 2450);
FORCEPROP 2 LAST SIG_NAME FM_SLPS4_N
J 2
(-4975 2460);
DISPLAY 0.617021 (-4975 2460);
PAINT ORANGE (-4975 2460);
WIRE 3 682 (-7050 2500)(-7050 2200);
WIRE 3 682 (-6550 2500)(-7050 2500);
WIRE 3 682 (-7050 2200)(-6550 2200);
WIRE 3 682 (-6550 2200)(-6550 2500);
WIRE 16 -1 (-6450 3850)(-4600 3850);
FORCEPROP 2 LAST SIG_NAME VCCBAT_TW12
J 0
(-5835 3860);
DISPLAY 0.680851 (-5835 3860);
PAINT ORANGE (-5835 3860);
FORCEPROP 2 LASTPROP $XRERR UNIQUE?
J 0
(-6075 3860);
DISPLAY 0.638298 (-6075 3860);
PAINT MONO (-6075 3860);
DISPLAY INVISIBLE (-6075 3860);
WIRE 16 -1 (-5250 2500)(-4600 2500);
FORCEPROP 2 LAST SIG_NAME BMC_JTAG_SEL_N
J 0
(-5210 2510);
DISPLAY 0.638298 (-5210 2510);
PAINT ORANGE (-5210 2510);
DOT 1 (-5700 1800);
DOT 1 (-5700 1850);
DOT 1 (-2350 2050);
DOT 1 (-4950 3500);
DOT 1 (-4750 3700);
DOT 1 (-4950 3350);
DOT 1 (-4950 3300);
DOT 1 (-4950 3250);
DOT 1 (-2350 3800);
DOT 1 (-5700 900);
DOT 1 (-6000 4250);
DOT 1 (-2350 3900);
DOT 1 (-2350 4400);
DOT 1 (-2350 3400);
DOT 1 (-2350 3350);
DOT 1 (-2350 3300);
DOT 1 (-2350 3250);
DOT 1 (-2350 3100);
DOT 1 (-2350 2850);
DOT 1 (-2350 2800);
DOT 1 (-2350 2750);
DOT 1 (-2350 2650);
DOT 1 (-2350 2400);
DOT 1 (-2350 2350);
DOT 1 (-2350 850);
DOT 1 (-2350 800);
DOT 1 (-2350 900);
DOT 1 (-2350 950);
DOT 1 (-2350 1000);
DOT 1 (-2350 1050);
DOT 1 (-2350 1100);
DOT 1 (-2350 1150);
DOT 1 (-2350 1200);
DOT 1 (-2350 1250);
DOT 1 (-2350 1300);
DOT 1 (-2350 1400);
DOT 1 (-2350 1350);
DOT 1 (-2350 1500);
DOT 1 (-2350 1450);
DOT 1 (-2350 1550);
DOT 1 (-2350 1600);
DOT 1 (-2350 1650);
DOT 1 (-2350 1750);
DOT 1 (-2350 1700);
DOT 1 (-2350 1800);
DOT 1 (-2350 1900);
DOT 1 (-2350 1850);
DOT 1 (-2350 2000);
DOT 1 (-2350 1950);
DOT 1 (-2350 2150);
DOT 1 (-2350 2100);
DOT 1 (-2350 2200);
DOT 1 (-2350 2300);
DOT 1 (-2350 2250);
DOT 1 (-2350 2450);
DOT 1 (-2350 2500);
DOT 1 (-2350 2550);
DOT 1 (-2350 2600);
DOT 1 (-2350 2700);
DOT 1 (-2350 2900);
DOT 1 (-2350 2950);
DOT 1 (-2350 3050);
DOT 1 (-2350 3000);
DOT 1 (-2350 3200);
DOT 1 (-2350 3150);
DOT 1 (-2350 3450);
DOT 1 (-2350 3500);
DOT 1 (-2350 3550);
DOT 1 (-2350 3600);
DOT 1 (-2350 3650);
DOT 1 (-2350 3700);
DOT 1 (-2350 3750);
DOT 1 (-2350 3850);
DOT 1 (-2350 3950);
DOT 1 (-2350 4050);
DOT 1 (-2350 4000);
DOT 1 (-2350 700);
DOT 1 (-2350 750);
DOT 1 (-5700 750);
DOT 1 (-5700 800);
DOT 1 (-5700 850);
DOT 1 (-5700 1000);
DOT 1 (-5700 950);
DOT 1 (-5700 1050);
DOT 1 (-5700 1150);
DOT 1 (-5700 1100);
DOT 1 (-5700 1200);
DOT 1 (-5700 1250);
DOT 1 (-5700 1300);
DOT 1 (-5700 1400);
DOT 1 (-5700 1350);
DOT 1 (-5700 1450);
DOT 1 (-5700 1550);
DOT 1 (-5700 1500);
DOT 1 (-5700 1600);
DOT 1 (-5700 1700);
DOT 1 (-5700 1750);
DOT 1 (-5700 1900);
DOT 1 (-4700 2000);
DOT 1 (-5700 2150);
DOT 1 (-5675 2700);
DOT 1 (-5675 2650);
DOT 1 (-5675 2800);
DOT 1 (-5675 2750);
DOT 1 (-4950 2950);
DOT 1 (-4950 3000);
DOT 1 (-4950 3050);
DOT 1 (-4950 3100);
DOT 1 (-4950 3150);
DOT 1 (-4950 3200);
DOT 1 (-4950 3450);
DOT 1 (-4950 3400);
DOT 1 (-4950 3600);
DOT 1 (-4700 3950);
DOT 1 (-4825 4450);
DOT 1 (-4825 4500);
DOT 1 (-4825 4550);
DOT 1 (-7350 2300);
DOT 1 (-5700 2100);
DOT 1 (-5700 1650);
FORCENOTE
TP FAB3 DELETE VCC_D_PLL_3V3 AND CONNECT PV33D13 TO VCC_PA_3V3 0922
(-6350 3550) 0;
DISPLAY LEFT (-6350 3550);
DISPLAY 0.638298 (-6350 3550);
PAINT RED (-6350 3550);
FORCENOTE
TP FAB1 ADD RES 0314
(-7075 2525) 0;
DISPLAY LEFT (-7075 2525);
DISPLAY 1.021277 (-7075 2525);
PAINT RED (-7075 2525);
FORCENOTE
POWER PIN T11 (OLD NAME: PV33D) SUPPLIES THE DDR PHY PLL POWER.
(-7425 3425) 0;
DISPLAY LEFT (-7425 3425);
DISPLAY 1.021277 (-7425 3425);
PAINT RED (-7425 3425);
FORCENOTE
ROOM=SM_CONTROLLER
(-7833 298) 0;
DISPLAY LEFT (-7833 298);
DISPLAY 0.617021 (-7833 298);
PAINT PURPLE (-7833 298);
QUIT
